# T6G (Grand Teton) — schematic netlist excerpt (pin names and nets, part order shuffled) for the footprints in the layout excerpt that follows; sources: Cadence DE-HDL packaged netlist, KiCad conversion of 04192023_DAF0TMB3IC0_F0TG_MB_C_brd_V02_OCP.brd

R4188  Q_RES  1K 1% EMPTY  pkg 0402LF  page 235 : A = P3V3_AUX ; B = U271_1_ADD2

(kicad_pcb
	(version 20260206)
	(generator "pcbnew")
	(generator_version "10.0")
	(general
		(thickness 1.6)
		(legacy_teardrops no)
	)
	(paper "A4")
	(title_block
		(title "04192023_DAF0TMB3IC0_F0TG_MB_C_brd_V02_OCP.brd")
		(comment 1 "Grand Teton / footprints 2360-2360 of 8354")
	)
	(layers
		(0 "F.Cu" signal "TOP")
		(4 "In1.Cu" signal "GND")
		(6 "In2.Cu" signal "IN1")
		(8 "In3.Cu" signal "GND1")
		(10 "In4.Cu" signal "IN2")
		(12 "In5.Cu" signal "GND2")
		(14 "In6.Cu" signal "IN3")
		(16 "In7.Cu" signal "GND3")
		(18 "In8.Cu" signal "VCC")
		(20 "In9.Cu" signal "VCC1")
		(22 "In10.Cu" signal "GND4")
		(24 "In11.Cu" signal "IN4")
		(26 "In12.Cu" signal "GND5")
		(28 "In13.Cu" signal "IN5")
		(30 "In14.Cu" signal "GND6")
		(32 "In15.Cu" signal "IN6")
		(34 "In16.Cu" signal "GND7")
		(2 "B.Cu" signal "BOTTOM")
		(9 "F.Adhes" user "F.Adhesive")
		(11 "B.Adhes" user "B.Adhesive")
		(13 "F.Paste" user "Package Geometry/Pastemask Top")
		(15 "B.Paste" user "Package Geometry/Pastemask Bottom")
		(5 "F.SilkS" user "Ref Des/Silkscreen Top")
		(7 "B.SilkS" user "Ref Des/Silkscreen Bottom")
		(1 "F.Mask" user "Board Geometry/Soldermask Top")
		(3 "B.Mask" user "Board Geometry/Soldermask Bottom")
		(17 "Dwgs.User" user "User.Drawings")
		(19 "Cmts.User" user "User.Comments")
		(21 "Eco1.User" user "User.Eco1")
		(23 "Eco2.User" user "User.Eco2")
		(25 "Edge.Cuts" user "Board Geometry/Outline")
		(27 "Margin" user)
		(31 "F.CrtYd" user "Package Geometry/Place Bound Top")
		(29 "B.CrtYd" user "Package Geometry/Place Bound Bottom")
		(35 "F.Fab" user "Ref Des/Assembly Top")
		(33 "B.Fab" user "Ref Des/Assembly Bottom")
	)
	(footprint ""
		(layer "F.Cu")
		(at 299.772578 -13.41501 180)
		(property "Reference" "R4188"
			(at 0 0 180)
			(layer "F.SilkS")
			(hide yes)
			(effects
				(font
					(size 1.27 1.27)
				)
			)
		)
		(property "Value" ""
			(at 0 0 180)
			(layer "F.Fab")
			(effects
				(font
					(size 1.27 1.27)
				)
			)
		)
		(duplicate_pad_numbers_are_jumpers no)
		(fp_line
			(start 0.7874 0.4064)
			(end -0.7874 0.4064)
			(stroke
				(width 0.1524)
				(type default)
			)
			(layer "F.SilkS")
		)
		(fp_line
			(start 0.7874 -0.4064)
			(end 0.7874 0.4064)
			(stroke
				(width 0.1524)
				(type default)
			)
			(layer "F.SilkS")
		)
		(fp_line
			(start -0.7874 0.4064)
			(end -0.7874 -0.4064)
			(stroke
				(width 0.1524)
				(type default)
			)
			(layer "F.SilkS")
		)
		(fp_line
			(start -0.7874 -0.4064)
			(end 0.7874 -0.4064)
			(stroke
				(width 0.1524)
				(type default)
			)
			(layer "F.SilkS")
		)
		(fp_line
			(start 0.67945 0.3048)
			(end 0.120396 0.3048)
			(stroke
				(width 0.1)
				(type default)
			)
			(layer "F.Fab")
		)
		(fp_line
			(start 0.67945 -0.3048)
			(end 0.67945 0.3048)
			(stroke
				(width 0.1)
				(type default)
			)
			(layer "F.Fab")
		)
		(fp_line
			(start 0.12065 -0.2794)
			(end 0.12065 -0.3048)
			(stroke
				(width 0.1)
				(type default)
			)
			(layer "F.Fab")
		)
		(fp_line
			(start 0.12065 -0.3048)
			(end 0.67945 -0.3048)
			(stroke
				(width 0.1)
				(type default)
			)
			(layer "F.Fab")
		)
		(fp_line
			(start 0.120396 0.3048)
			(end 0.120396 0.2794)
			(stroke
				(width 0.1)
				(type default)
			)
			(layer "F.Fab")
		)
		(fp_line
			(start 0.120396 0.2794)
			(end -0.12065 0.2794)
			(stroke
				(width 0.1)
				(type default)
			)
			(layer "F.Fab")
		)
		(fp_line
			(start -0.12065 0.3048)
			(end -0.67945 0.3048)
			(stroke
				(width 0.1)
				(type default)
			)
			(layer "F.Fab")
		)
		(fp_line
			(start -0.12065 0.2794)
			(end -0.12065 0.3048)
			(stroke
				(width 0.1)
				(type default)
			)
			(layer "F.Fab")
		)
		(fp_line
			(start -0.12065 -0.2794)
			(end 0.12065 -0.2794)
			(stroke
				(width 0.1)
				(type default)
			)
			(layer "F.Fab")
		)
		(fp_line
			(start -0.12065 -0.305054)
			(end -0.12065 -0.2794)
			(stroke
				(width 0.1)
				(type default)
			)
			(layer "F.Fab")
		)
		(fp_line
			(start -0.67945 0.3048)
			(end -0.67945 -0.305054)
			(stroke
				(width 0.1)
				(type default)
			)
			(layer "F.Fab")
		)
		(fp_line
			(start -0.67945 -0.305054)
			(end -0.12065 -0.305054)
			(stroke
				(width 0.1)
				(type default)
			)
			(layer "F.Fab")
		)
		(pad "1" smd circle
			(at -0.40005 0 180)
			(size 0 0)
			(layers "F.Cu" "F.Mask" "F.Paste")
			(net "P3V3_AUX")
		)
		(pad "2" smd circle
			(at 0.40005 0 180)
			(size 0 0)
			(layers "F.Cu" "F.Mask" "F.Paste")
			(net "U271_1_ADD2")
		)
	)
)
